FILE_TYPE=LIBRARY_PARTS;
primitive 'SCONN20_513860200CV01';
  pin
    '1':
      PIN_NUMBER='(1)';
      BIDIRECTIONAL='TRUE';
      INPUT_LOAD='(-0.01,0.01)';
      OUTPUT_LOAD='(1.0,-1.0)';
    '2':
      PIN_NUMBER='(2)';
      BIDIRECTIONAL='TRUE';
      INPUT_LOAD='(-0.01,0.01)';
      OUTPUT_LOAD='(1.0,-1.0)';
    '3':
      PIN_NUMBER='(3)';
      BIDIRECTIONAL='TRUE';
      INPUT_LOAD='(-0.01,0.01)';
      OUTPUT_LOAD='(1.0,-1.0)';
    '4':
      PIN_NUMBER='(4)';
      BIDIRECTIONAL='TRUE';
      INPUT_LOAD='(-0.01,0.01)';
      OUTPUT_LOAD='(1.0,-1.0)';
    '5':
      PIN_NUMBER='(5)';
      BIDIRECTIONAL='TRUE';
      INPUT_LOAD='(-0.01,0.01)';
      OUTPUT_LOAD='(1.0,-1.0)';
    '6':
      PIN_NUMBER='(6)';
      BIDIRECTIONAL='TRUE';
      INPUT_LOAD='(-0.01,0.01)';
      OUTPUT_LOAD='(1.0,-1.0)';
    '7':
      PIN_NUMBER='(7)';
      BIDIRECTIONAL='TRUE';
      INPUT_LOAD='(-0.01,0.01)';
      OUTPUT_LOAD='(1.0,-1.0)';
    '8':
      PIN_NUMBER='(8)';
      BIDIRECTIONAL='TRUE';
      INPUT_LOAD='(-0.01,0.01)';
      OUTPUT_LOAD='(1.0,-1.0)';
    '9':
      PIN_NUMBER='(9)';
      BIDIRECTIONAL='TRUE';
      INPUT_LOAD='(-0.01,0.01)';
      OUTPUT_LOAD='(1.0,-1.0)';
    '10':
      PIN_NUMBER='(10)';
      BIDIRECTIONAL='TRUE';
      INPUT_LOAD='(-0.01,0.01)';
      OUTPUT_LOAD='(1.0,-1.0)';
    '11':
      PIN_NUMBER='(11)';
      BIDIRECTIONAL='TRUE';
      INPUT_LOAD='(-0.01,0.01)';
      OUTPUT_LOAD='(1.0,-1.0)';
    '12':
      PIN_NUMBER='(12)';
      BIDIRECTIONAL='TRUE';
      INPUT_LOAD='(-0.01,0.01)';
      OUTPUT_LOAD='(1.0,-1.0)';
    '13':
      PIN_NUMBER='(13)';
      BIDIRECTIONAL='TRUE';
      INPUT_LOAD='(-0.01,0.01)';
      OUTPUT_LOAD='(1.0,-1.0)';
    '14':
      PIN_NUMBER='(14)';
      BIDIRECTIONAL='TRUE';
      INPUT_LOAD='(-0.01,0.01)';
      OUTPUT_LOAD='(1.0,-1.0)';
    '15':
      PIN_NUMBER='(15)';
      BIDIRECTIONAL='TRUE';
      INPUT_LOAD='(-0.01,0.01)';
      OUTPUT_LOAD='(1.0,-1.0)';
    '16':
      PIN_NUMBER='(16)';
      BIDIRECTIONAL='TRUE';
      INPUT_LOAD='(-0.01,0.01)';
      OUTPUT_LOAD='(1.0,-1.0)';
    '17':
      PIN_NUMBER='(17)';
      BIDIRECTIONAL='TRUE';
      INPUT_LOAD='(-0.01,0.01)';
      OUTPUT_LOAD='(1.0,-1.0)';
    '18':
      PIN_NUMBER='(18)';
      BIDIRECTIONAL='TRUE';
      INPUT_LOAD='(-0.01,0.01)';
      OUTPUT_LOAD='(1.0,-1.0)';
    '19':
      PIN_NUMBER='(19)';
      BIDIRECTIONAL='TRUE';
      INPUT_LOAD='(-0.01,0.01)';
      OUTPUT_LOAD='(1.0,-1.0)';
    '20':
      PIN_NUMBER='(20)';
      BIDIRECTIONAL='TRUE';
      INPUT_LOAD='(-0.01,0.01)';
      OUTPUT_LOAD='(1.0,-1.0)';
  end_pin;
  body
    PART_NAME='SCONN20_513860200CV01';
    BODY_NAME='SCONN20_513860200CV01';
    PHYS_DES_PREFIX='J';
    CLASS='IO';
    NC_PINS='(H1,H2)';
  end_body;
end_primitive;

END.
